G04*
G04 #@! TF.GenerationSoftware,Altium Limited,Altium Designer,23.0.1 (38)*
G04*
G04 Layer_Physical_Order=1*
G04 Layer_Color=255*
%FSLAX44Y44*%
%MOMM*%
G71*
G04*
G04 #@! TF.SameCoordinates,9A23C038-B079-480F-8166-AFFB5740F5AE*
G04*
G04*
G04 #@! TF.FilePolarity,Positive*
G04*
G01*
G75*
%ADD10C,0.1778*%
%ADD20R,1.2700X0.5588*%
%ADD21R,0.9000X0.6000*%
%ADD22R,0.5000X0.6000*%
%ADD23R,0.8000X0.8000*%
%ADD24R,0.5000X0.4000*%
%ADD25R,2.9500X1.0200*%
%ADD26R,5.0000X1.0000*%
%ADD27C,1.0000*%
%ADD28R,0.5000X0.5000*%
%ADD29R,0.5000X0.5000*%
%ADD30R,0.6000X0.5000*%
%ADD42C,0.0127*%
%ADD43R,0.8001X1.7983*%
%ADD44C,0.2540*%
%ADD45C,0.5080*%
%ADD46C,0.5500*%
%ADD47C,0.5588*%
G36*
X662899Y313154D02*
X664122Y312648D01*
X665223Y311913D01*
X666159Y310977D01*
X666895Y309878D01*
X667402Y308655D01*
X667661Y307358D01*
X667662Y306697D01*
X667632Y10150D01*
X667632Y10150D01*
X667632Y10150D01*
X667632Y9548D01*
X667397Y8368D01*
X666937Y7257D01*
X666269Y6256D01*
X665419Y5405D01*
X664419Y4736D01*
X663307Y4275D01*
X662128Y4039D01*
X661526Y4038D01*
X10450Y4078D01*
X10450Y4078D01*
X10450Y4078D01*
X9822D01*
X8591Y4323D01*
X7432Y4803D01*
X6388Y5501D01*
X5501Y6388D01*
X4803Y7432D01*
X4323Y8591D01*
X4078Y9822D01*
X4078Y10450D01*
X4078Y10450D01*
X4078Y10450D01*
X4058Y306760D01*
X4058Y307413D01*
X4313Y308693D01*
X4812Y309900D01*
X5537Y310985D01*
X6460Y311909D01*
X7545Y312635D01*
X8751Y313135D01*
X10031Y313391D01*
X10684Y313392D01*
X660940Y313412D01*
X661602D01*
X662899Y313154D01*
D02*
G37*
%LPC*%
G36*
X635037Y308538D02*
X631983D01*
X631589Y308460D01*
X631188D01*
X628193Y307864D01*
X627822Y307711D01*
X627428Y307632D01*
X624607Y306464D01*
X624273Y306241D01*
X623902Y306087D01*
X621363Y304391D01*
X621079Y304107D01*
X620746Y303883D01*
X618587Y301724D01*
X618363Y301390D01*
X618079Y301106D01*
X616383Y298568D01*
X616229Y298197D01*
X616006Y297863D01*
X614838Y295042D01*
X614759Y294648D01*
X614606Y294277D01*
X614010Y291282D01*
Y290881D01*
X613932Y290487D01*
Y287433D01*
X614010Y287039D01*
Y286638D01*
X614606Y283643D01*
X614759Y283272D01*
X614838Y282878D01*
X616006Y280057D01*
X616229Y279723D01*
X616383Y279352D01*
X618079Y276814D01*
X618363Y276529D01*
X618587Y276196D01*
X620746Y274037D01*
X621079Y273813D01*
X621363Y273529D01*
X623902Y271833D01*
X624273Y271679D01*
X624607Y271456D01*
X627428Y270288D01*
X627822Y270209D01*
X628193Y270056D01*
X631188Y269460D01*
X631589D01*
X631983Y269382D01*
X635037D01*
X635431Y269460D01*
X635832D01*
X638827Y270056D01*
X639198Y270209D01*
X639592Y270288D01*
X642413Y271456D01*
X642747Y271679D01*
X643118Y271833D01*
X645657Y273529D01*
X645941Y273813D01*
X646274Y274037D01*
X648434Y276196D01*
X648657Y276530D01*
X648941Y276814D01*
X650637Y279352D01*
X650791Y279723D01*
X651014Y280057D01*
X652182Y282878D01*
X652261Y283272D01*
X652414Y283643D01*
X653010Y286638D01*
Y287039D01*
X653088Y287433D01*
Y290487D01*
X653010Y290881D01*
Y291282D01*
X652414Y294277D01*
X652261Y294648D01*
X652182Y295042D01*
X651014Y297863D01*
X650791Y298197D01*
X650637Y298568D01*
X648941Y301106D01*
X648657Y301391D01*
X648434Y301724D01*
X646274Y303883D01*
X645940Y304107D01*
X645657Y304391D01*
X643118Y306087D01*
X642747Y306241D01*
X642413Y306464D01*
X639592Y307632D01*
X639198Y307711D01*
X638827Y307864D01*
X635832Y308460D01*
X635431D01*
X635037Y308538D01*
D02*
G37*
G36*
X30037D02*
X26983D01*
X26589Y308460D01*
X26188D01*
X23193Y307864D01*
X22822Y307711D01*
X22428Y307632D01*
X19607Y306464D01*
X19273Y306241D01*
X18902Y306087D01*
X16364Y304391D01*
X16079Y304107D01*
X15746Y303883D01*
X13586Y301724D01*
X13363Y301390D01*
X13079Y301106D01*
X11383Y298568D01*
X11229Y298197D01*
X11006Y297863D01*
X9838Y295042D01*
X9759Y294648D01*
X9606Y294277D01*
X9010Y291282D01*
Y290881D01*
X8932Y290487D01*
Y287433D01*
X9010Y287039D01*
Y286638D01*
X9606Y283643D01*
X9759Y283272D01*
X9838Y282878D01*
X11006Y280057D01*
X11229Y279723D01*
X11383Y279352D01*
X13079Y276814D01*
X13363Y276529D01*
X13586Y276196D01*
X15746Y274037D01*
X16079Y273813D01*
X16364Y273529D01*
X18902Y271833D01*
X19273Y271679D01*
X19607Y271456D01*
X22428Y270288D01*
X22822Y270209D01*
X23193Y270056D01*
X26188Y269460D01*
X26589D01*
X26983Y269382D01*
X30037D01*
X30431Y269460D01*
X30832D01*
X33827Y270056D01*
X34198Y270209D01*
X34592Y270288D01*
X37413Y271456D01*
X37747Y271679D01*
X38118Y271833D01*
X40656Y273529D01*
X40941Y273813D01*
X41274Y274037D01*
X43433Y276196D01*
X43657Y276530D01*
X43941Y276814D01*
X45637Y279352D01*
X45791Y279723D01*
X46014Y280057D01*
X47182Y282878D01*
X47261Y283272D01*
X47414Y283643D01*
X48010Y286638D01*
Y287039D01*
X48088Y287433D01*
Y290487D01*
X48010Y290881D01*
Y291282D01*
X47414Y294277D01*
X47261Y294648D01*
X47182Y295042D01*
X46014Y297863D01*
X45791Y298197D01*
X45637Y298568D01*
X43941Y301106D01*
X43657Y301391D01*
X43433Y301724D01*
X41274Y303883D01*
X40940Y304107D01*
X40656Y304391D01*
X38118Y306087D01*
X37747Y306241D01*
X37413Y306464D01*
X34592Y307632D01*
X34198Y307711D01*
X33827Y307864D01*
X30832Y308460D01*
X30431D01*
X30037Y308538D01*
D02*
G37*
G36*
X394540Y259540D02*
Y256540D01*
X397040D01*
Y259540D01*
X394540D01*
D02*
G37*
G36*
X252509Y253500D02*
X243508D01*
Y251950D01*
X208570D01*
X208529Y251958D01*
Y251976D01*
X204090Y251627D01*
X199761Y250588D01*
X195647Y248884D01*
X191850Y246557D01*
X188464Y243665D01*
X188478Y243652D01*
X188455Y243618D01*
X152362Y207525D01*
X152283Y207406D01*
X148984Y204698D01*
X145095Y202620D01*
X140876Y201340D01*
X136629Y200922D01*
X136488Y200950D01*
X112377D01*
Y202000D01*
X103377D01*
Y200950D01*
X68261D01*
X67248Y203395D01*
X66377Y204530D01*
X66305Y204637D01*
X66260Y204683D01*
X65533Y205630D01*
X64586Y206357D01*
X64540Y206403D01*
X64432Y206475D01*
X63298Y207345D01*
X60695Y208423D01*
X59277Y208610D01*
X59150Y208635D01*
X59085D01*
X57902Y208791D01*
X56718Y208635D01*
X56653D01*
X56526Y208610D01*
X55109Y208423D01*
X52506Y207345D01*
X51371Y206475D01*
X51264Y206403D01*
X51218Y206357D01*
X50271Y205630D01*
X49544Y204683D01*
X49498Y204637D01*
X49426Y204530D01*
X48556Y203395D01*
X47478Y200792D01*
X47291Y199374D01*
X47266Y199248D01*
Y199183D01*
X47110Y197999D01*
X47266Y196816D01*
Y196751D01*
X47291Y196624D01*
X47478Y195206D01*
X48556Y192603D01*
X49426Y191469D01*
X49498Y191361D01*
X49544Y191315D01*
X50271Y190368D01*
X51218Y189642D01*
X51264Y189596D01*
X51372Y189524D01*
X52506Y188653D01*
X55109Y187575D01*
X56527Y187388D01*
X56653Y187363D01*
X56718D01*
X57902Y187207D01*
X59085Y187363D01*
X59150D01*
X59277Y187388D01*
X60695Y187575D01*
X63298Y188653D01*
X64432Y189524D01*
X64540Y189596D01*
X64586Y189642D01*
X65533Y190368D01*
X66259Y191315D01*
X66305Y191361D01*
X66377Y191469D01*
X67248Y192603D01*
X68261Y195051D01*
X102847D01*
X103377Y194000D01*
Y190648D01*
X103248Y190000D01*
Y177819D01*
X103248Y177819D01*
X103411Y176998D01*
Y174844D01*
X103411Y174844D01*
X103500Y174396D01*
Y169384D01*
X116500D01*
Y169755D01*
X127383D01*
X128032Y169883D01*
X131914Y169883D01*
X132960Y169343D01*
X133546Y169343D01*
X135460D01*
Y174383D01*
Y179424D01*
X132960D01*
X131914Y178883D01*
X128032Y178883D01*
X127383Y179012D01*
X116500D01*
Y179384D01*
X112506D01*
Y190000D01*
X112377Y190648D01*
Y194000D01*
X112907Y195051D01*
X136447D01*
X136488Y195042D01*
Y195024D01*
X140927Y195373D01*
X145256Y196413D01*
X149370Y198116D01*
X153167Y200443D01*
X156553Y203335D01*
X156553Y203335D01*
X157430Y204250D01*
X192655Y239475D01*
X192735Y239594D01*
X196033Y242302D01*
X199922Y244380D01*
X204142Y245660D01*
X208389Y246078D01*
X208529Y246050D01*
X243508D01*
Y244770D01*
X243508Y244500D01*
Y243500D01*
X243508Y243230D01*
Y234500D01*
X245063D01*
Y226990D01*
X243551D01*
Y227530D01*
X239550D01*
Y215998D01*
Y204466D01*
X243551D01*
Y205007D01*
X252466D01*
Y204466D01*
X256467D01*
Y215998D01*
Y227530D01*
X252466D01*
Y226990D01*
X250954D01*
Y234500D01*
X252509D01*
Y243230D01*
X252509Y243500D01*
Y244500D01*
X252509Y244770D01*
Y253500D01*
D02*
G37*
G36*
X290460Y253040D02*
X287460D01*
Y250540D01*
X290460D01*
Y253040D01*
D02*
G37*
G36*
X397040Y251460D02*
X394540D01*
Y248460D01*
X397040D01*
Y251460D01*
D02*
G37*
G36*
X234470Y227530D02*
X230470D01*
Y218538D01*
X234470D01*
Y227530D01*
D02*
G37*
G36*
X93462Y235917D02*
X22342D01*
X21537Y235757D01*
X20854Y235301D01*
X20398Y234618D01*
X20238Y233813D01*
Y210191D01*
X20398Y209386D01*
X20854Y208703D01*
X21537Y208247D01*
X22342Y208087D01*
X41487D01*
X42255Y208240D01*
X42292Y208247D01*
X42295Y208249D01*
X42975Y208703D01*
X43228Y208897D01*
X43229Y208898D01*
X43229Y208898D01*
X44930Y210971D01*
X47710Y213252D01*
X50882Y214948D01*
X54323Y215991D01*
X57902Y216344D01*
X61481Y215991D01*
X64922Y214948D01*
X68094Y213252D01*
X70873Y210971D01*
X72575Y208898D01*
X72575Y208898D01*
X72575Y208897D01*
X72828Y208703D01*
X73509Y208249D01*
X73511Y208247D01*
X73549Y208240D01*
X74316Y208087D01*
X93462D01*
X94267Y208247D01*
X94950Y208703D01*
X95406Y209386D01*
X95566Y210191D01*
Y233813D01*
X95406Y234618D01*
X94950Y235301D01*
X94267Y235757D01*
X93462Y235917D01*
D02*
G37*
G36*
X234470Y213458D02*
X230470D01*
Y204466D01*
X234470D01*
Y213458D01*
D02*
G37*
G36*
X93462Y187911D02*
X74316D01*
X73549Y187759D01*
X73511Y187751D01*
X73509Y187750D01*
X72828Y187295D01*
X72575Y187101D01*
X72575Y187101D01*
X72575Y187101D01*
X70873Y185027D01*
X68094Y182746D01*
X64922Y181051D01*
X61481Y180007D01*
X57902Y179654D01*
X54323Y180007D01*
X50882Y181051D01*
X47710Y182746D01*
X44930Y185027D01*
X43229Y187101D01*
X43229Y187101D01*
X43228Y187101D01*
X42975Y187295D01*
X42295Y187750D01*
X42292Y187751D01*
X42255Y187759D01*
X41487Y187911D01*
X22342D01*
X21537Y187751D01*
X20854Y187295D01*
X20398Y186612D01*
X20238Y185807D01*
Y162185D01*
X20398Y161380D01*
X20854Y160697D01*
X21537Y160241D01*
X22342Y160081D01*
X93462D01*
X94267Y160241D01*
X94950Y160697D01*
X95406Y161380D01*
X95566Y162185D01*
Y185807D01*
X95406Y186612D01*
X94950Y187295D01*
X94267Y187751D01*
X93462Y187911D01*
D02*
G37*
G36*
X140540Y179424D02*
Y176923D01*
X143040D01*
Y179424D01*
X140540D01*
D02*
G37*
G36*
X143040Y171843D02*
X140540D01*
Y169343D01*
X143040D01*
Y171843D01*
D02*
G37*
G36*
X585410Y150440D02*
X570660D01*
Y147429D01*
X561006D01*
X560000Y147629D01*
X558229Y147277D01*
X556727Y146273D01*
X555723Y144771D01*
X555371Y143000D01*
X555723Y141229D01*
X556727Y139727D01*
X556927Y139527D01*
X556927Y139527D01*
X558429Y138523D01*
X560200Y138171D01*
X570660D01*
Y135160D01*
X585410D01*
Y142800D01*
X587950D01*
D01*
X585410D01*
Y150440D01*
D02*
G37*
G36*
X605240D02*
X590490D01*
Y145340D01*
X605240D01*
Y150440D01*
D02*
G37*
G36*
Y140260D02*
X590490D01*
Y135160D01*
X605240D01*
Y140260D01*
D02*
G37*
G36*
X492965Y275334D02*
X286000D01*
X284724Y275080D01*
X283643Y274357D01*
X278646Y269361D01*
X277923Y268279D01*
X277669Y267003D01*
Y226990D01*
X265547D01*
Y227530D01*
X261547D01*
Y215998D01*
Y204466D01*
X265547D01*
Y205007D01*
X287004D01*
Y226990D01*
X284337D01*
Y265622D01*
X287381Y268666D01*
X371292D01*
X371778Y267493D01*
X352643Y248358D01*
X351920Y247276D01*
X351666Y246000D01*
Y240280D01*
X351176Y240096D01*
X350396Y240060D01*
X349596Y241445D01*
X348293Y242748D01*
X346697Y243669D01*
X344917Y244146D01*
X343074D01*
X341293Y243669D01*
X339697Y242748D01*
X338394Y241445D01*
X337601Y240072D01*
X336717Y240140D01*
X336331Y240289D01*
Y246840D01*
X337298Y247399D01*
X338601Y248702D01*
X339523Y250298D01*
X340000Y252078D01*
Y253922D01*
X339523Y255702D01*
X338601Y257298D01*
X337298Y258601D01*
X335702Y259523D01*
X333922Y260000D01*
X332078D01*
X330298Y259523D01*
X328702Y258601D01*
X327399Y257298D01*
X326477Y255702D01*
X326000Y253922D01*
Y252078D01*
X326477Y250298D01*
X327399Y248702D01*
X328702Y247399D01*
X329663Y246844D01*
Y240289D01*
X329277Y240140D01*
X328393Y240072D01*
X327600Y241445D01*
X326297Y242748D01*
X324701Y243669D01*
X322920Y244146D01*
X321077D01*
X319297Y243669D01*
X317701Y242748D01*
X316397Y241445D01*
X315605Y240072D01*
X314721Y240140D01*
X314335Y240289D01*
Y246842D01*
X315299Y247399D01*
X316602Y248702D01*
X317523Y250298D01*
X318001Y252078D01*
Y253922D01*
X317523Y255702D01*
X316602Y257298D01*
X315299Y258601D01*
X313702Y259523D01*
X311922Y260000D01*
X310079D01*
X308299Y259523D01*
X306702Y258601D01*
X305399Y257298D01*
X304478Y255702D01*
X304000Y253922D01*
Y252078D01*
X304289Y251003D01*
X299713Y246428D01*
X298540Y246914D01*
Y253040D01*
X295540D01*
Y248000D01*
X293000D01*
Y245460D01*
X287460D01*
Y242960D01*
X287460D01*
X288000Y241914D01*
Y233500D01*
X298000D01*
Y236049D01*
X298506Y236150D01*
X299588Y236872D01*
X306493Y243778D01*
X307666Y243291D01*
Y226990D01*
X305000D01*
Y205007D01*
X382990D01*
Y226990D01*
X380324D01*
Y230421D01*
X381078Y231000D01*
X382922D01*
X384702Y231477D01*
X386298Y232399D01*
X387601Y233702D01*
X388523Y235298D01*
X389000Y237078D01*
Y238922D01*
X388523Y240702D01*
X387601Y242298D01*
X386298Y243601D01*
X384702Y244523D01*
X382922Y245000D01*
X381078D01*
X379298Y244523D01*
X378673Y244162D01*
X377894Y245179D01*
X381715Y249000D01*
X385914Y249000D01*
X386960Y248460D01*
X387546Y248460D01*
X389460D01*
Y254000D01*
Y259540D01*
X386960D01*
X385914Y259000D01*
X377500Y259000D01*
Y254215D01*
X367997Y244712D01*
X366922Y245000D01*
X365078D01*
X363298Y244523D01*
X361702Y243601D01*
X360399Y242298D01*
X359604Y240922D01*
X358749Y240981D01*
X358334Y241140D01*
Y244619D01*
X377381Y263666D01*
X479619D01*
X511252Y232033D01*
X512334Y231310D01*
X513610Y231056D01*
X531536D01*
X531973Y230000D01*
X533099Y228874D01*
X532867Y227881D01*
X532710Y227604D01*
X454270D01*
X452994Y227350D01*
X451912Y226628D01*
X332792Y107507D01*
X332069Y106425D01*
X331815Y105149D01*
Y104993D01*
X305000D01*
Y83010D01*
X307666D01*
Y79677D01*
X306633Y78809D01*
X305922Y79000D01*
X304078D01*
X302298Y78523D01*
X300702Y77601D01*
X299399Y76298D01*
X298477Y74702D01*
X298000Y72922D01*
Y71078D01*
X298477Y69298D01*
X299399Y67702D01*
X300702Y66399D01*
X302298Y65477D01*
X304078Y65000D01*
X305922D01*
X307702Y65477D01*
X309298Y66399D01*
X310601Y67702D01*
X311523Y69298D01*
X312000Y71078D01*
Y72922D01*
X311712Y73997D01*
X313358Y75643D01*
X314081Y76725D01*
X314335Y78000D01*
Y83010D01*
X318666D01*
Y78158D01*
X317702Y77601D01*
X316399Y76298D01*
X315477Y74702D01*
X315000Y72922D01*
Y71078D01*
X315477Y69298D01*
X316399Y67702D01*
X317702Y66399D01*
X319298Y65477D01*
X321078Y65000D01*
X322922D01*
X324702Y65477D01*
X326298Y66399D01*
X327601Y67702D01*
X328523Y69298D01*
X329000Y71078D01*
Y72922D01*
X328523Y74702D01*
X327601Y76298D01*
X326298Y77601D01*
X325334Y78158D01*
Y83010D01*
X346518D01*
X346961Y82470D01*
Y77040D01*
X347116Y76260D01*
X347421Y75803D01*
Y72000D01*
X347500Y71602D01*
Y68086D01*
X346960Y67040D01*
X346960Y67040D01*
X346960Y67040D01*
Y64540D01*
X352000D01*
X357040D01*
Y65923D01*
X357040Y66961D01*
X357879Y66961D01*
X362517D01*
Y64540D01*
X367557D01*
X372597D01*
Y66961D01*
X377110D01*
X377950Y66961D01*
Y64540D01*
X382990D01*
X388030D01*
Y67040D01*
X388030D01*
X387490Y68086D01*
Y69954D01*
X433987Y116451D01*
X435492D01*
Y106246D01*
X447492D01*
Y109371D01*
X452327D01*
X453460Y109040D01*
X453460Y108101D01*
Y106540D01*
X459000D01*
X464540D01*
Y109040D01*
X464000Y110086D01*
X464000Y116451D01*
X484740D01*
X504492Y96700D01*
Y91246D01*
X509945D01*
X521665Y79527D01*
X522365Y79059D01*
X521980Y77789D01*
X446121D01*
Y91246D01*
X447492D01*
Y103246D01*
X435492D01*
Y91246D01*
X436863D01*
Y73160D01*
Y48893D01*
X421599Y33629D01*
X244917D01*
X155773Y122773D01*
X155473Y122973D01*
X155273Y123273D01*
X155273Y123273D01*
X139002Y139544D01*
Y142611D01*
X140272Y143137D01*
X213767Y69643D01*
X214849Y68920D01*
X216124Y68666D01*
X216500D01*
Y67000D01*
X225230D01*
X225500Y67000D01*
X226500D01*
X226770Y67000D01*
X235500D01*
Y68666D01*
X241842D01*
X242399Y67702D01*
X243702Y66399D01*
X245298Y65477D01*
X247078Y65000D01*
X248922D01*
X250702Y65477D01*
X252298Y66399D01*
X253601Y67702D01*
X254523Y69298D01*
X255000Y71078D01*
Y72922D01*
X254523Y74702D01*
X253601Y76298D01*
X252298Y77601D01*
X251343Y78153D01*
Y83010D01*
X287004D01*
Y104993D01*
X243551D01*
Y105534D01*
X239550D01*
Y94002D01*
Y82470D01*
X243551D01*
Y82470D01*
X244674Y82117D01*
Y78163D01*
X243702Y77601D01*
X242399Y76298D01*
X241842Y75334D01*
X235500D01*
Y77000D01*
X226770D01*
X226500Y77000D01*
X225500D01*
X225230Y77000D01*
X216500D01*
X216500Y77000D01*
Y77000D01*
X215396Y77444D01*
X142712Y150127D01*
X141630Y150850D01*
X140354Y151104D01*
X123645D01*
X122370Y150850D01*
X121288Y150128D01*
X118674Y147514D01*
X117952Y146432D01*
X117698Y145156D01*
Y134794D01*
X114629D01*
Y154383D01*
X116500D01*
Y164384D01*
X103500D01*
Y154383D01*
X105371D01*
Y134794D01*
X102998D01*
Y125206D01*
X119698D01*
Y128928D01*
X120871Y129414D01*
X123371Y126914D01*
X122878Y125644D01*
X122302D01*
Y120898D01*
X122242Y120596D01*
Y116547D01*
X121723Y115771D01*
X121371Y114000D01*
X121371Y114000D01*
Y108629D01*
X109500D01*
Y109000D01*
X101086Y109000D01*
X100040Y109540D01*
X99454Y109540D01*
X97540D01*
Y104000D01*
Y98460D01*
X100040D01*
X101086Y99000D01*
X109500Y99000D01*
Y99371D01*
X121500D01*
Y99000D01*
X130500D01*
Y99000D01*
X131500D01*
Y99000D01*
X140500D01*
Y101954D01*
X152000Y113454D01*
X239727Y25727D01*
X239727Y25727D01*
X241229Y24723D01*
X243000Y24371D01*
X423516D01*
X423516Y24371D01*
X425288Y24723D01*
X426789Y25727D01*
X444765Y43703D01*
X444765Y43703D01*
X445769Y45204D01*
X446121Y46976D01*
X446121Y46976D01*
Y68531D01*
X604580D01*
X604581Y68531D01*
X606352Y68883D01*
X607854Y69887D01*
X610513Y72546D01*
X610513Y72546D01*
X611517Y74048D01*
X611869Y75819D01*
X611869Y75820D01*
Y77907D01*
X612133Y78171D01*
X616700D01*
Y75700D01*
X650200D01*
Y89900D01*
X616700D01*
Y87429D01*
X610216D01*
X608445Y87077D01*
X606943Y86073D01*
X606943Y86073D01*
X605873Y85004D01*
X604700Y85490D01*
Y89900D01*
X571200D01*
Y87429D01*
X526855D01*
X516492Y97792D01*
Y103246D01*
X511038D01*
X509212Y105073D01*
X509698Y106246D01*
X516492D01*
Y109371D01*
X521327D01*
X522460Y109040D01*
X522460Y108101D01*
Y106540D01*
X528000D01*
X533540D01*
Y109040D01*
X533000Y110086D01*
X533000Y118500D01*
X528648D01*
X528000Y118629D01*
X514928D01*
X514928Y118629D01*
X513450Y118335D01*
X511952D01*
X511505Y118246D01*
X504492D01*
Y111452D01*
X503319Y110966D01*
X489931Y124353D01*
X488429Y125357D01*
X486658Y125709D01*
X486658Y125709D01*
X432070D01*
X432070Y125709D01*
X430298Y125357D01*
X428797Y124353D01*
X428797Y124353D01*
X385758Y81315D01*
X384226Y81442D01*
X384183Y81471D01*
X383530Y82470D01*
Y91462D01*
X376990D01*
Y94002D01*
X374450D01*
Y105534D01*
X370449D01*
Y104993D01*
X354368D01*
X353882Y106167D01*
X460381Y212666D01*
X519113D01*
X519639Y211396D01*
X518973Y210730D01*
X518250Y208984D01*
Y207094D01*
X518973Y205349D01*
X519666Y204656D01*
Y141000D01*
X519920Y139724D01*
X520643Y138643D01*
X556250Y103035D01*
Y102055D01*
X556973Y100309D01*
X558309Y98973D01*
X560055Y98250D01*
X561945D01*
X563691Y98973D01*
X564383Y99666D01*
X571200D01*
Y95700D01*
X604700D01*
Y109900D01*
X571200D01*
Y106334D01*
X564383D01*
X563691Y107027D01*
X561945Y107750D01*
X560965D01*
X526334Y142381D01*
Y204656D01*
X527027Y205349D01*
X527750Y207094D01*
Y208984D01*
X527027Y210730D01*
X526361Y211396D01*
X526887Y212666D01*
X532152D01*
X532678Y211396D01*
X531973Y210691D01*
X531250Y208945D01*
Y207055D01*
X531973Y205309D01*
X532666Y204617D01*
Y148000D01*
X532920Y146724D01*
X533643Y145642D01*
X556250Y123035D01*
Y122055D01*
X556973Y120309D01*
X558309Y118973D01*
X560055Y118250D01*
X561945D01*
X563691Y118973D01*
X564183Y119466D01*
X571200D01*
Y115700D01*
X604700D01*
Y129900D01*
X571200D01*
Y126134D01*
X564584D01*
X563691Y127027D01*
X561945Y127750D01*
X560965D01*
X539334Y149381D01*
Y204617D01*
X540027Y205309D01*
X540750Y207055D01*
Y208945D01*
X540027Y210691D01*
X539322Y211396D01*
X539848Y212666D01*
X578901D01*
X579458Y211702D01*
X580761Y210399D01*
X581725Y209842D01*
Y204500D01*
X580060D01*
Y195770D01*
X580059Y195500D01*
Y194500D01*
X580060Y194230D01*
Y185500D01*
X581725D01*
Y177941D01*
X581979Y176665D01*
X582702Y175583D01*
X607666Y150619D01*
Y136000D01*
X607920Y134724D01*
X608643Y133643D01*
X616611Y125674D01*
Y125360D01*
X616611Y125360D01*
X616700Y124913D01*
Y115700D01*
X650200D01*
Y129900D01*
X623216D01*
X623012Y130036D01*
X621348Y130367D01*
X617285Y134430D01*
X617811Y135700D01*
X650200D01*
Y149900D01*
X616700D01*
Y136811D01*
X615430Y136285D01*
X614334Y137381D01*
Y152000D01*
X614080Y153276D01*
X613358Y154358D01*
X588394Y179321D01*
Y185500D01*
X590059D01*
Y194230D01*
X590060Y194500D01*
Y195500D01*
X590059Y195770D01*
Y204500D01*
X588394D01*
Y209842D01*
X589357Y210399D01*
X590661Y211702D01*
X591582Y213298D01*
X592059Y215078D01*
Y216922D01*
X591582Y218702D01*
X591026Y219666D01*
X591757Y220936D01*
X602349D01*
X604269Y219016D01*
X604088Y218702D01*
X603611Y216922D01*
Y215078D01*
X604088Y213298D01*
X605009Y211702D01*
X606313Y210399D01*
X607277Y209842D01*
Y204500D01*
X605611D01*
Y195770D01*
X605611Y195500D01*
Y194500D01*
X605611Y194230D01*
Y185500D01*
X615611D01*
Y186666D01*
X619619D01*
X652666Y153619D01*
Y109717D01*
X651643Y108694D01*
X650200D01*
Y109900D01*
X636457D01*
X636010Y109989D01*
X635563Y109900D01*
X616700D01*
Y95700D01*
X650200D01*
Y102026D01*
X653024D01*
X654300Y102280D01*
X655382Y103002D01*
X658357Y105978D01*
X659080Y107060D01*
X659334Y108336D01*
Y155000D01*
X659080Y156276D01*
X658357Y157358D01*
X623358Y192358D01*
X622276Y193080D01*
X621000Y193334D01*
X616510D01*
X615611Y194500D01*
Y195500D01*
X615611Y195770D01*
Y204500D01*
X613945D01*
Y209842D01*
X614909Y210399D01*
X616212Y211702D01*
X617134Y213298D01*
X617611Y215078D01*
Y216922D01*
X617134Y218702D01*
X616212Y220298D01*
X614909Y221601D01*
X613313Y222523D01*
X611533Y223000D01*
X609715D01*
X606087Y226628D01*
X605006Y227350D01*
X603730Y227604D01*
X539290D01*
X539133Y227881D01*
X538901Y228874D01*
X540027Y230000D01*
X540750Y231746D01*
Y233636D01*
X540027Y235381D01*
X538691Y236717D01*
X536945Y237441D01*
X535055D01*
X534910Y237381D01*
X534776Y237470D01*
X533500Y237724D01*
X527203D01*
X526677Y238994D01*
X526992Y239309D01*
X527715Y241055D01*
Y242945D01*
X526992Y244691D01*
X525656Y246027D01*
X523910Y246750D01*
X522930D01*
X495323Y274357D01*
X494241Y275080D01*
X492965Y275334D01*
D02*
G37*
G36*
X92460Y109540D02*
X89960D01*
Y106540D01*
X92460D01*
Y109540D01*
D02*
G37*
G36*
X533540Y101460D02*
X530540D01*
Y98960D01*
X533540D01*
Y101460D01*
D02*
G37*
G36*
X525460D02*
X522460D01*
Y98960D01*
X525460D01*
Y101460D01*
D02*
G37*
G36*
X464540Y101460D02*
X461540D01*
Y98960D01*
X464540D01*
Y101460D01*
D02*
G37*
G36*
X456460D02*
X453460D01*
Y98960D01*
X456460D01*
Y101460D01*
D02*
G37*
G36*
X92460Y101460D02*
X89960D01*
Y98460D01*
X92460D01*
Y101460D01*
D02*
G37*
G36*
X383530Y105534D02*
X379530D01*
Y96542D01*
X383530D01*
Y105534D01*
D02*
G37*
G36*
X234470D02*
X230470D01*
Y96542D01*
X234470D01*
Y105534D01*
D02*
G37*
G36*
Y91462D02*
X230470D01*
Y82470D01*
X234470D01*
Y91462D01*
D02*
G37*
G36*
X388030Y59460D02*
X385530D01*
Y56960D01*
X388030D01*
Y59460D01*
D02*
G37*
G36*
X380450D02*
X377950D01*
Y56960D01*
X380450D01*
Y59460D01*
D02*
G37*
G36*
X372597Y59460D02*
X370097D01*
Y56960D01*
X372597D01*
Y59460D01*
D02*
G37*
G36*
X365017D02*
X362517D01*
Y56960D01*
X365017D01*
Y59460D01*
D02*
G37*
G36*
X357040Y59460D02*
X354540D01*
Y56960D01*
X357040D01*
Y59460D01*
D02*
G37*
G36*
X349460D02*
X346960D01*
Y56960D01*
X349460D01*
Y59460D01*
D02*
G37*
G36*
X635037Y48538D02*
X631983D01*
X631589Y48460D01*
X631188D01*
X628193Y47864D01*
X627822Y47711D01*
X627428Y47632D01*
X624607Y46464D01*
X624273Y46241D01*
X623902Y46087D01*
X621363Y44391D01*
X621079Y44107D01*
X620746Y43884D01*
X618587Y41725D01*
X618363Y41391D01*
X618079Y41107D01*
X616383Y38568D01*
X616229Y38197D01*
X616006Y37863D01*
X614838Y35042D01*
X614759Y34648D01*
X614606Y34277D01*
X614010Y31282D01*
Y30881D01*
X613932Y30487D01*
Y27433D01*
X614010Y27039D01*
Y26638D01*
X614606Y23643D01*
X614759Y23272D01*
X614838Y22878D01*
X616006Y20057D01*
X616229Y19723D01*
X616383Y19352D01*
X618079Y16813D01*
X618363Y16529D01*
X618587Y16195D01*
X620746Y14037D01*
X621079Y13813D01*
X621363Y13529D01*
X623902Y11833D01*
X624273Y11679D01*
X624607Y11456D01*
X627428Y10288D01*
X627822Y10209D01*
X628193Y10056D01*
X631188Y9460D01*
X631589D01*
X631983Y9382D01*
X635037D01*
X635431Y9460D01*
X635832D01*
X638827Y10056D01*
X639198Y10209D01*
X639592Y10288D01*
X642413Y11456D01*
X642747Y11679D01*
X643118Y11833D01*
X645657Y13529D01*
X645941Y13813D01*
X646274Y14037D01*
X648434Y16195D01*
X648657Y16530D01*
X648941Y16813D01*
X650637Y19352D01*
X650791Y19723D01*
X651014Y20057D01*
X652182Y22878D01*
X652261Y23272D01*
X652414Y23643D01*
X653010Y26638D01*
Y27039D01*
X653088Y27433D01*
Y30487D01*
X653010Y30881D01*
Y31282D01*
X652414Y34277D01*
X652261Y34648D01*
X652182Y35042D01*
X651014Y37863D01*
X650791Y38197D01*
X650637Y38568D01*
X648941Y41107D01*
X648657Y41391D01*
X648434Y41725D01*
X646274Y43884D01*
X645940Y44107D01*
X645657Y44391D01*
X643118Y46087D01*
X642747Y46241D01*
X642413Y46464D01*
X639592Y47632D01*
X639198Y47711D01*
X638827Y47864D01*
X635832Y48460D01*
X635431D01*
X635037Y48538D01*
D02*
G37*
G36*
X30037D02*
X26983D01*
X26589Y48460D01*
X26188D01*
X23193Y47864D01*
X22822Y47711D01*
X22428Y47632D01*
X19607Y46464D01*
X19273Y46241D01*
X18902Y46087D01*
X16364Y44391D01*
X16079Y44107D01*
X15746Y43884D01*
X13586Y41725D01*
X13363Y41391D01*
X13079Y41107D01*
X11383Y38568D01*
X11229Y38197D01*
X11006Y37863D01*
X9838Y35042D01*
X9759Y34648D01*
X9606Y34277D01*
X9010Y31282D01*
Y30881D01*
X8932Y30487D01*
Y27433D01*
X9010Y27039D01*
Y26638D01*
X9606Y23643D01*
X9759Y23272D01*
X9838Y22878D01*
X11006Y20057D01*
X11229Y19723D01*
X11383Y19352D01*
X13079Y16813D01*
X13363Y16529D01*
X13586Y16195D01*
X15746Y14037D01*
X16079Y13813D01*
X16364Y13529D01*
X18902Y11833D01*
X19273Y11679D01*
X19607Y11456D01*
X22428Y10288D01*
X22822Y10209D01*
X23193Y10056D01*
X26188Y9460D01*
X26589D01*
X26983Y9382D01*
X30037D01*
X30431Y9460D01*
X30832D01*
X33827Y10056D01*
X34198Y10209D01*
X34592Y10288D01*
X37413Y11456D01*
X37747Y11679D01*
X38118Y11833D01*
X40656Y13529D01*
X40941Y13813D01*
X41274Y14037D01*
X43433Y16195D01*
X43657Y16530D01*
X43941Y16813D01*
X45637Y19352D01*
X45791Y19723D01*
X46014Y20057D01*
X47182Y22878D01*
X47261Y23272D01*
X47414Y23643D01*
X48010Y26638D01*
Y27039D01*
X48088Y27433D01*
Y30487D01*
X48010Y30881D01*
Y31282D01*
X47414Y34277D01*
X47261Y34648D01*
X47182Y35042D01*
X46014Y37863D01*
X45791Y38197D01*
X45637Y38568D01*
X43941Y41107D01*
X43657Y41391D01*
X43433Y41725D01*
X41274Y43884D01*
X40940Y44107D01*
X40656Y44391D01*
X38118Y46087D01*
X37747Y46241D01*
X37413Y46464D01*
X34592Y47632D01*
X34198Y47711D01*
X33827Y47864D01*
X30832Y48460D01*
X30431D01*
X30037Y48538D01*
D02*
G37*
%LPD*%
G36*
X60421Y206303D02*
X61993Y205652D01*
X63407Y204707D01*
X64610Y203504D01*
X65555Y202090D01*
X66206Y200518D01*
X66538Y198850D01*
Y197999D01*
Y197149D01*
X66206Y195480D01*
X65555Y193909D01*
X64610Y192494D01*
X63407Y191291D01*
X61993Y190346D01*
X60421Y189695D01*
X58752Y189363D01*
X57051D01*
X55383Y189695D01*
X53811Y190346D01*
X52397Y191291D01*
X51194Y192494D01*
X50249Y193909D01*
X49598Y195480D01*
X49266Y197149D01*
Y197999D01*
Y198850D01*
X49598Y200518D01*
X50249Y202090D01*
X51194Y203504D01*
X52397Y204707D01*
X53811Y205652D01*
X55383Y206303D01*
X57051Y206635D01*
X58752D01*
X60421Y206303D01*
D02*
G37*
G36*
X93462Y210191D02*
X74316D01*
X73321Y211428D01*
X71058Y213652D01*
X68478Y215498D01*
X65644Y216924D01*
X62623Y217894D01*
X59488Y218385D01*
X56315D01*
X53181Y217894D01*
X50160Y216924D01*
X47326Y215498D01*
X44746Y213652D01*
X42483Y211428D01*
X41487Y210191D01*
X22342D01*
Y233813D01*
X93462D01*
Y210191D01*
D02*
G37*
G36*
Y162185D02*
X22342D01*
Y185807D01*
X41487D01*
X41487Y185807D01*
X42483Y184570D01*
X44746Y182347D01*
X47326Y180500D01*
X50160Y179074D01*
X53181Y178105D01*
X56315Y177614D01*
X59488D01*
X62623Y178105D01*
X65644Y179074D01*
X68478Y180500D01*
X71058Y182347D01*
X73321Y184570D01*
X74316Y185807D01*
X93462Y185807D01*
Y162185D01*
D02*
G37*
G36*
X368531Y82470D02*
X370000D01*
Y80000D01*
X382784D01*
X383270Y78827D01*
X381483Y77040D01*
X377950D01*
Y74540D01*
X382990D01*
Y69460D01*
X377950D01*
Y69000D01*
X372597D01*
Y69460D01*
X367557D01*
X362517D01*
Y69000D01*
X357040D01*
Y69460D01*
X352000D01*
Y72000D01*
X349460D01*
Y77040D01*
X349000D01*
Y82470D01*
X352453D01*
Y94002D01*
X357533D01*
Y82470D01*
X363451D01*
Y94002D01*
X368531D01*
Y82470D01*
D02*
G37*
%LPC*%
G36*
X357040Y77040D02*
X354540D01*
Y74540D01*
X357040D01*
Y77040D01*
D02*
G37*
G36*
X372597D02*
X370097D01*
Y74540D01*
X372597D01*
Y77040D01*
D02*
G37*
G36*
X365017D02*
X362517D01*
Y74540D01*
X365017D01*
Y77040D01*
D02*
G37*
%LPD*%
D10*
X136488Y198000D02*
G03*
X154448Y205440I0J25400D01*
G01*
X208529Y249000D02*
G03*
X190569Y241560I0J-25400D01*
G01*
X154448Y205440D02*
X190569Y241560D01*
X208529Y249000D02*
X248008D01*
Y215998D02*
Y239000D01*
X57900Y198000D02*
X136488D01*
D20*
X130652Y120850D02*
D03*
Y139150D02*
D03*
X111348Y130000D02*
D03*
D21*
X110000Y174384D02*
D03*
Y159383D02*
D03*
D22*
X95000Y104000D02*
D03*
X105000D02*
D03*
X382000Y254000D02*
D03*
X392000D02*
D03*
X136000Y104000D02*
D03*
X126000D02*
D03*
X221000Y72000D02*
D03*
X231000D02*
D03*
D23*
X510492Y112246D02*
D03*
Y97246D02*
D03*
X441492Y112246D02*
D03*
Y97246D02*
D03*
D24*
X107877Y190000D02*
D03*
Y198000D02*
D03*
D25*
X633450Y82800D02*
D03*
Y102800D02*
D03*
Y122800D02*
D03*
Y142800D02*
D03*
X587950Y82800D02*
D03*
Y102800D02*
D03*
Y122800D02*
D03*
Y142800D02*
D03*
D26*
X57900Y168839D02*
D03*
X55360Y225940D02*
D03*
D27*
X610611Y216000D02*
D03*
X57902Y197999D02*
D03*
X366000Y238000D02*
D03*
X333000Y253000D02*
D03*
X321999Y237146D02*
D03*
X311000Y253000D02*
D03*
X343995Y237146D02*
D03*
X248000Y72000D02*
D03*
X382000Y238000D02*
D03*
X305000Y72000D02*
D03*
X322000D02*
D03*
X585060Y216000D02*
D03*
D28*
X138000Y174384D02*
D03*
X128000D02*
D03*
D29*
X352000Y62000D02*
D03*
Y72000D02*
D03*
X367557Y62000D02*
D03*
Y72000D02*
D03*
X382990Y62000D02*
D03*
Y72000D02*
D03*
X248008Y249000D02*
D03*
Y239000D02*
D03*
D30*
X293000Y248000D02*
D03*
Y238000D02*
D03*
X459000Y114000D02*
D03*
Y104000D02*
D03*
X528000Y114000D02*
D03*
Y104000D02*
D03*
X585060Y190000D02*
D03*
Y200000D02*
D03*
X610611Y190000D02*
D03*
Y200000D02*
D03*
D42*
X41487Y185807D02*
G03*
X74316Y185807I16415J12192D01*
G01*
Y210191D02*
G03*
X41487Y210191I-16415J-12192D01*
G01*
X66538Y197999D02*
G03*
X66538Y197999I-8636J0D01*
G01*
X74316Y185807D02*
X93462D01*
Y210191D02*
Y233813D01*
X22342Y210191D02*
Y233813D01*
X74316Y210191D02*
X93462D01*
X22342Y162185D02*
Y185807D01*
Y233813D02*
X93462D01*
X22342Y210191D02*
X41487D01*
X22342Y185807D02*
X41487D01*
X93462Y162185D02*
Y185807D01*
X22342Y162185D02*
X93462D01*
D43*
X311000Y215998D02*
D03*
X354993D02*
D03*
X365992D02*
D03*
X376990D02*
D03*
X321999D02*
D03*
X332997D02*
D03*
X343995D02*
D03*
X281003D02*
D03*
X248008D02*
D03*
X259007D02*
D03*
X270005D02*
D03*
X237010D02*
D03*
X270005Y94002D02*
D03*
X248008D02*
D03*
X237010D02*
D03*
X281003D02*
D03*
X259007D02*
D03*
X343995D02*
D03*
X332997D02*
D03*
X321999D02*
D03*
X376990D02*
D03*
X365992D02*
D03*
X354993D02*
D03*
X311000D02*
D03*
D44*
X523000Y141000D02*
Y208039D01*
X492965Y272000D02*
X522965Y242000D01*
X286000Y272000D02*
X492965D01*
X513610Y234390D02*
X533500D01*
X535199Y232691D01*
X481000Y267000D02*
X513610Y234390D01*
X535199Y232691D02*
X536000D01*
X127053Y122374D02*
X128577Y120850D01*
X130652D01*
X127053Y122374D02*
Y127947D01*
X121032Y133968D02*
X127053Y127947D01*
X121032Y133968D02*
Y145156D01*
X123645Y147770D01*
X216124Y72000D02*
X221000D01*
X231000D02*
X231000Y72000D01*
X248000D01*
X123645Y147770D02*
X140354D01*
X216124Y72000D01*
X346726Y103726D02*
X459000Y216000D01*
X585060D01*
X346726Y96732D02*
Y103726D01*
X308854Y250853D02*
X311000Y248706D01*
X308854Y250853D02*
X308854D01*
X308725Y250981D02*
X308854Y250853D01*
X308725Y250981D02*
Y253000D01*
X297230Y239230D02*
X311000Y253000D01*
X294230Y239230D02*
X297230D01*
X293000Y238000D02*
X294230Y239230D01*
X536000Y148000D02*
X561000Y123000D01*
X536000Y148000D02*
Y208000D01*
X376000Y267000D02*
X481000D01*
X335149Y105149D02*
X454270Y224270D01*
X603730D01*
X610611Y217389D01*
X355000Y246000D02*
X376000Y267000D01*
X281003Y267003D02*
X286000Y272000D01*
X355000Y216005D02*
Y246000D01*
X523000Y141000D02*
X561000Y103000D01*
X281003Y215998D02*
Y267003D01*
X343995Y94002D02*
X346726Y96732D01*
X332997Y94002D02*
X335149Y96154D01*
Y105149D01*
X610611Y200000D02*
Y217389D01*
X585060Y200000D02*
Y216000D01*
X656000Y108336D02*
Y155000D01*
X610611Y190000D02*
X621000D01*
X656000Y155000D01*
X636010Y105360D02*
X653024D01*
X656000Y108336D01*
X611000Y136000D02*
X621240Y125760D01*
X585060Y177941D02*
Y190000D01*
Y177941D02*
X611000Y152000D01*
Y136000D02*
Y152000D01*
X343995Y237146D02*
X344000Y237151D01*
X382000Y237792D02*
Y238000D01*
X366000D02*
X380270Y252270D01*
X380770D01*
X382000Y253500D01*
Y254000D01*
X332997Y215998D02*
Y253002D01*
X321000Y237146D02*
X321999Y236148D01*
X366000Y216007D02*
Y238000D01*
X376990Y232782D02*
X382000Y237792D01*
X343995Y215998D02*
Y237995D01*
X376990Y215998D02*
Y232782D01*
X354993Y215998D02*
X355000Y216005D01*
X311000Y78000D02*
Y94002D01*
X321999Y215998D02*
Y236148D01*
X311000Y215998D02*
Y248706D01*
X321999Y94002D02*
X322000Y94001D01*
X248000Y72000D02*
X248008Y72009D01*
X305000Y72000D02*
X311000Y78000D01*
X322000Y72000D02*
Y94001D01*
X248008Y72009D02*
Y94002D01*
X561000Y103000D02*
X587750D01*
X561000Y123000D02*
X561200Y122800D01*
X587950D01*
X587750Y103000D02*
X587950Y102800D01*
D45*
X134462Y137538D02*
Y138896D01*
X136460Y104460D02*
X152000Y120000D01*
X152500Y119500D02*
X243000Y29000D01*
X136040Y104460D02*
X136460D01*
X243000Y29000D02*
X423516D01*
X152000Y120000D02*
Y120000D01*
X134462Y137538D02*
X152000Y120000D01*
X136000Y104000D02*
Y104420D01*
X136040Y104460D01*
X126000Y104000D02*
Y114000D01*
X126871Y114871D01*
Y120596D01*
X130784D01*
X105000Y104000D02*
X126000D01*
X510492Y97246D02*
X524938Y82800D01*
X486658Y121080D02*
X510492Y97246D01*
X432070Y121080D02*
X486658D01*
X382990Y72000D02*
X432070Y121080D01*
X633450Y102800D02*
X636010Y105360D01*
X621240Y125360D02*
X623800Y122800D01*
X633450D01*
X621240Y125360D02*
Y125760D01*
X441492Y73160D02*
Y97246D01*
Y73160D02*
X604581D01*
X441492Y46976D02*
Y73160D01*
X604581D02*
X607240Y75819D01*
X423516Y29000D02*
X441492Y46976D01*
X607240Y75819D02*
Y79824D01*
X610216Y82800D02*
X633450D01*
X607240Y79824D02*
X610216Y82800D01*
X110000Y174384D02*
X127383D01*
X110000Y130000D02*
Y159383D01*
X108040Y174844D02*
X108500Y174384D01*
X107877Y177819D02*
Y190000D01*
Y177819D02*
X108040Y177656D01*
Y174844D02*
Y177656D01*
X108500Y174384D02*
X110000D01*
X510492Y112246D02*
X511952Y113706D01*
X514634D01*
X514928Y114000D01*
X528000D01*
X445928D02*
X459000D01*
X441492Y112246D02*
X442952Y113706D01*
X445634D01*
X445928Y114000D01*
X524938Y82800D02*
X587950D01*
X560200Y142800D02*
X587950D01*
X560000Y143000D02*
X560200Y142800D01*
D46*
X523000Y208039D02*
D03*
X522965Y242000D02*
D03*
X536000Y232691D02*
D03*
X241871Y254805D02*
D03*
X231291D02*
D03*
X220711D02*
D03*
X210131D02*
D03*
X199634Y253481D02*
D03*
X190160Y248771D02*
D03*
X182390Y241591D02*
D03*
X174908Y234110D02*
D03*
X167427Y226629D02*
D03*
X159946Y219147D02*
D03*
X152465Y211666D02*
D03*
X144033Y205276D02*
D03*
X133555Y203805D02*
D03*
X122976D02*
D03*
X112410Y204354D02*
D03*
X101844Y203805D02*
D03*
X91264D02*
D03*
X80684D02*
D03*
X70105Y203927D02*
D03*
X62147Y210899D02*
D03*
X51602Y210033D02*
D03*
X44897Y201849D02*
D03*
X46109Y191339D02*
D03*
X54498Y184892D02*
D03*
X64966Y186424D02*
D03*
X73834Y192195D02*
D03*
X84414D02*
D03*
X94994D02*
D03*
X116052D02*
D03*
X126632D02*
D03*
X137212Y192229D02*
D03*
X147587Y194300D02*
D03*
X156682Y199706D02*
D03*
X164283Y207065D02*
D03*
X171765Y214546D02*
D03*
X179246Y222027D02*
D03*
X186727Y229508D02*
D03*
X194208Y236989D02*
D03*
X203283Y242429D02*
D03*
X213835Y243195D02*
D03*
X224415D02*
D03*
X234995D02*
D03*
X255209Y245785D02*
D03*
X252362Y255974D02*
D03*
X536000Y208000D02*
D03*
X561000Y103000D02*
D03*
Y123000D02*
D03*
X560000Y143000D02*
D03*
D47*
X175640Y128600D02*
D03*
X124840Y154000D02*
D03*
X150240Y103200D02*
D03*
X404029Y103411D02*
D03*
X455040Y128600D02*
D03*
X429640D02*
D03*
X404240D02*
D03*
X302640Y230200D02*
D03*
X632840Y255600D02*
D03*
Y230200D02*
D03*
Y204800D02*
D03*
Y154000D02*
D03*
Y52400D02*
D03*
X607440Y281000D02*
D03*
Y255600D02*
D03*
Y230200D02*
D03*
Y179400D02*
D03*
Y52400D02*
D03*
Y27000D02*
D03*
X582040Y281000D02*
D03*
Y255600D02*
D03*
Y154000D02*
D03*
Y52400D02*
D03*
X556640Y281000D02*
D03*
Y255600D02*
D03*
Y204800D02*
D03*
Y179400D02*
D03*
Y154000D02*
D03*
Y52400D02*
D03*
X531240Y281000D02*
D03*
Y255600D02*
D03*
Y52400D02*
D03*
X505840Y281000D02*
D03*
Y204800D02*
D03*
Y179400D02*
D03*
Y154000D02*
D03*
Y128600D02*
D03*
Y52400D02*
D03*
X480440Y281000D02*
D03*
Y255600D02*
D03*
Y204800D02*
D03*
Y179400D02*
D03*
Y154000D02*
D03*
Y128600D02*
D03*
Y103200D02*
D03*
Y52400D02*
D03*
X455040Y281000D02*
D03*
Y255600D02*
D03*
Y179400D02*
D03*
Y154000D02*
D03*
Y52400D02*
D03*
X429640Y281000D02*
D03*
Y255600D02*
D03*
Y230200D02*
D03*
Y154000D02*
D03*
Y103200D02*
D03*
Y77800D02*
D03*
Y52400D02*
D03*
X404240Y281000D02*
D03*
Y255600D02*
D03*
Y230200D02*
D03*
Y204800D02*
D03*
Y77800D02*
D03*
Y52400D02*
D03*
X378840Y281000D02*
D03*
Y179400D02*
D03*
Y52400D02*
D03*
X353440Y281000D02*
D03*
Y255600D02*
D03*
Y179400D02*
D03*
Y154000D02*
D03*
Y52400D02*
D03*
X328040Y281000D02*
D03*
Y179400D02*
D03*
Y154000D02*
D03*
Y128600D02*
D03*
Y52400D02*
D03*
X302640Y281000D02*
D03*
Y179400D02*
D03*
Y154000D02*
D03*
Y128600D02*
D03*
Y52400D02*
D03*
X277240Y281000D02*
D03*
Y179400D02*
D03*
Y154000D02*
D03*
Y128600D02*
D03*
Y77800D02*
D03*
Y52400D02*
D03*
X251840Y281000D02*
D03*
Y179400D02*
D03*
Y154000D02*
D03*
Y128600D02*
D03*
Y52400D02*
D03*
X226440Y281000D02*
D03*
Y230200D02*
D03*
Y204800D02*
D03*
Y179400D02*
D03*
Y154000D02*
D03*
Y128600D02*
D03*
Y103200D02*
D03*
Y27000D02*
D03*
X201040Y281000D02*
D03*
Y230200D02*
D03*
Y204800D02*
D03*
Y179400D02*
D03*
Y154000D02*
D03*
Y128600D02*
D03*
Y103200D02*
D03*
Y52400D02*
D03*
Y27000D02*
D03*
X175640Y281000D02*
D03*
Y255600D02*
D03*
Y204800D02*
D03*
Y179400D02*
D03*
Y154000D02*
D03*
Y77800D02*
D03*
Y52400D02*
D03*
Y27000D02*
D03*
X150240Y281000D02*
D03*
Y255600D02*
D03*
Y230200D02*
D03*
Y179400D02*
D03*
Y154000D02*
D03*
Y77800D02*
D03*
Y52400D02*
D03*
Y27000D02*
D03*
X124840Y281000D02*
D03*
Y255600D02*
D03*
Y230200D02*
D03*
Y77800D02*
D03*
Y52400D02*
D03*
Y27000D02*
D03*
X99440Y281000D02*
D03*
Y255600D02*
D03*
Y154000D02*
D03*
Y77800D02*
D03*
Y52400D02*
D03*
Y27000D02*
D03*
X74040Y281000D02*
D03*
Y255600D02*
D03*
Y230200D02*
D03*
Y179400D02*
D03*
Y154000D02*
D03*
Y128600D02*
D03*
Y103200D02*
D03*
Y77800D02*
D03*
Y52400D02*
D03*
Y27000D02*
D03*
X48640Y255600D02*
D03*
Y154000D02*
D03*
Y128600D02*
D03*
Y103200D02*
D03*
Y77800D02*
D03*
Y52400D02*
D03*
X23240Y255600D02*
D03*
Y154000D02*
D03*
Y128600D02*
D03*
Y103200D02*
D03*
Y77800D02*
D03*
Y52400D02*
D03*
M02*
